(kicad_pcb
	(version 20260206)
	(generator "pcbnew")
	(generator_version "10.0")
	(general
		(thickness 1.6)
		(legacy_teardrops no)
	)
	(paper "A4")
	(title_block
		(title "Wiwynn_Tioga_Pass_MB.brd")
		(comment 1 "Tioga Pass / footprints 2164-2166 of 4770")
	)
	(layers
		(0 "F.Cu" signal "TOP")
		(4 "In1.Cu" signal "L2GND")
		(6 "In2.Cu" signal "L3")
		(8 "In3.Cu" signal "L4GND")
		(10 "In4.Cu" signal "L5")
		(12 "In5.Cu" signal "L6GND")
		(14 "In6.Cu" signal "L7VCC")
		(16 "In7.Cu" signal "L8VCC")
		(18 "In8.Cu" signal "L9GND")
		(20 "In9.Cu" signal "L10")
		(22 "In10.Cu" signal "L11GND")
		(24 "In11.Cu" signal "L12")
		(26 "In12.Cu" signal "L13GND")
		(2 "B.Cu" signal "BOTTOM")
		(9 "F.Adhes" user "F.Adhesive")
		(11 "B.Adhes" user "B.Adhesive")
		(13 "F.Paste" user "Package Geometry/Pastemask Top")
		(15 "B.Paste" user "Package Geometry/Pastemask Bottom")
		(5 "F.SilkS" user "Ref Des/Silkscreen Top")
		(7 "B.SilkS" user "Ref Des/Silkscreen Bottom")
		(1 "F.Mask" user "Board Geometry/Soldermask Top")
		(3 "B.Mask" user "Board Geometry/Soldermask Bottom")
		(17 "Dwgs.User" user "User.Drawings")
		(19 "Cmts.User" user "User.Comments")
		(21 "Eco1.User" user "User.Eco1")
		(23 "Eco2.User" user "User.Eco2")
		(25 "Edge.Cuts" user "Board Geometry/Outline")
		(27 "Margin" user)
		(31 "F.CrtYd" user "Package Geometry/Place Bound Top")
		(29 "B.CrtYd" user "Package Geometry/Place Bound Bottom")
		(35 "F.Fab" user "Ref Des/Assembly Top")
		(33 "B.Fab" user "Ref Des/Assembly Bottom")
	)
	(footprint ""
		(layer "F.Cu")
		(at 463.3849 -23.2791)
		(property "Reference" "R8F1"
			(at 0 0 0)
			(layer "F.SilkS")
			(hide yes)
			(effects
				(font
					(size 1.27 1.27)
				)
			)
		)
		(property "Value" ""
			(at 0 0 0)
			(layer "F.Fab")
			(effects
				(font
					(size 1.27 1.27)
				)
			)
		)
		(duplicate_pad_numbers_are_jumpers no)
		(fp_rect
			(start 0.2794 0.9906)
			(end -0.2794 -0.1016)
			(stroke
				(width 0)
				(type default)
			)
			(fill no)
			(layer "F.CrtYd")
		)
		(fp_line
			(start -0.2794 -0.1016)
			(end -0.2794 0.9906)
			(stroke
				(width 0.1)
				(type default)
			)
			(layer "F.Fab")
		)
		(fp_line
			(start -0.2794 0.9906)
			(end 0.2794 0.9906)
			(stroke
				(width 0.1)
				(type default)
			)
			(layer "F.Fab")
		)
		(fp_line
			(start 0.2794 -0.1016)
			(end -0.2794 -0.1016)
			(stroke
				(width 0.1)
				(type default)
			)
			(layer "F.Fab")
		)
		(fp_line
			(start 0.2794 0.9906)
			(end 0.2794 -0.1016)
			(stroke
				(width 0.1)
				(type default)
			)
			(layer "F.Fab")
		)
		(pad "1" smd rect
			(at 0 0)
			(size 0.508 0.508)
			(layers "F.Cu" "F.Mask" "F.Paste")
			(net "PWRGD_P5V_STBY")
		)
		(pad "2" smd rect
			(at 0 0.889)
			(size 0.508 0.508)
			(layers "F.Cu" "F.Mask" "F.Paste")
			(net "GND")
		)
		(zone
			(layer "F.Cu")
			(hatch none 0.5)
			(connect_pads
				(clearance 0)
			)
			(min_thickness 0.25)
			(keepout
				(tracks not_allowed)
				(vias allowed)
				(pads allowed)
				(copperpour not_allowed)
				(footprints allowed)
			)
			(placement
				(enabled no)
				(sheetname "")
			)
			(fill
				(thermal_gap 0.5)
				(thermal_bridge_width 0.5)
				(island_removal_mode 0)
			)
			(polygon
				(pts
					(xy 463.6389 -22.6441) (xy 463.6389 -23.0251) (xy 463.1309 -23.0251) (xy 463.1309 -22.6441)
				)
			)
		)
		(zone
			(layer "F.Cu")
			(hatch none 0.5)
			(connect_pads
				(clearance 0)
			)
			(min_thickness 0.25)
			(keepout
				(tracks allowed)
				(vias not_allowed)
				(pads allowed)
				(copperpour not_allowed)
				(footprints allowed)
			)
			(placement
				(enabled no)
				(sheetname "")
			)
			(fill
				(thermal_gap 0.5)
				(thermal_bridge_width 0.5)
				(island_removal_mode 0)
			)
			(polygon
				(pts
					(xy 463.6389 -22.6441) (xy 463.6389 -23.0251) (xy 463.1309 -23.0251) (xy 463.1309 -22.6441)
				)
			)
		)
	)
	(footprint ""
		(layer "F.Cu")
		(at 430.026826 -131.636008)
		(property "Reference" "R8B4"
			(at 0 0 0)
			(layer "F.SilkS")
			(hide yes)
			(effects
				(font
					(size 1.27 1.27)
				)
			)
		)
		(property "Value" ""
			(at 0 0 0)
			(layer "F.Fab")
			(effects
				(font
					(size 1.27 1.27)
				)
			)
		)
		(duplicate_pad_numbers_are_jumpers no)
		(fp_poly
			(pts
				(xy -0.2794 -0.1016) (xy 0.2794 -0.1016) (xy 0.2794 0.9906) (xy -0.2794 0.9906)
			)
			(stroke
				(width 0)
				(type default)
			)
			(fill no)
			(layer "F.CrtYd")
		)
		(fp_line
			(start -0.2794 -0.1016)
			(end -0.2794 0.9906)
			(stroke
				(width 0.1)
				(type default)
			)
			(layer "F.Fab")
		)
		(fp_line
			(start -0.2794 0.9906)
			(end 0.2794 0.9906)
			(stroke
				(width 0.1)
				(type default)
			)
			(layer "F.Fab")
		)
		(fp_line
			(start 0.2794 -0.1016)
			(end -0.2794 -0.1016)
			(stroke
				(width 0.1)
				(type default)
			)
			(layer "F.Fab")
		)
		(fp_line
			(start 0.2794 0.9906)
			(end 0.2794 -0.1016)
			(stroke
				(width 0.1)
				(type default)
			)
			(layer "F.Fab")
		)
		(pad "1" smd rect
			(at 0 0)
			(size 0.508 0.508)
			(layers "F.Cu" "F.Mask" "F.Paste")
			(net "FM_CTNR_PS_ON")
		)
		(pad "2" smd rect
			(at 0 0.889)
			(size 0.508 0.508)
			(layers "F.Cu" "F.Mask" "F.Paste")
			(net "GND")
		)
		(zone
			(layer "F.Cu")
			(hatch none 0.5)
			(connect_pads
				(clearance 0)
			)
			(min_thickness 0.25)
			(keepout
				(tracks allowed)
				(vias not_allowed)
				(pads allowed)
				(copperpour not_allowed)
				(footprints allowed)
			)
			(placement
				(enabled no)
				(sheetname "")
			)
			(fill
				(thermal_gap 0.5)
				(thermal_bridge_width 0.5)
				(island_removal_mode 0)
			)
			(polygon
				(pts
					(xy 429.772826 -131.382008) (xy 430.280826 -131.382008) (xy 430.280826 -131.001008) (xy 429.772826 -131.001008)
				)
			)
		)
		(zone
			(layer "F.Cu")
			(hatch none 0.5)
			(connect_pads
				(clearance 0)
			)
			(min_thickness 0.25)
			(keepout
				(tracks not_allowed)
				(vias allowed)
				(pads allowed)
				(copperpour not_allowed)
				(footprints allowed)
			)
			(placement
				(enabled no)
				(sheetname "")
			)
			(fill
				(thermal_gap 0.5)
				(thermal_bridge_width 0.5)
				(island_removal_mode 0)
			)
			(polygon
				(pts
					(xy 429.772826 -131.001008) (xy 430.280826 -131.001008) (xy 430.280826 -131.382008) (xy 429.772826 -131.382008)
				)
			)
		)
	)
	(footprint ""
		(layer "F.Cu")
		(at 108.712 -69.85)
		(property "Reference" "R3D32"
			(at 0 0 0)
			(layer "F.SilkS")
			(hide yes)
			(effects
				(font
					(size 1.27 1.27)
				)
			)
		)
		(property "Value" ""
			(at 0 0 0)
			(layer "F.Fab")
			(effects
				(font
					(size 1.27 1.27)
				)
			)
		)
		(duplicate_pad_numbers_are_jumpers no)
		(fp_poly
			(pts
				(xy -0.2794 -0.1016) (xy 0.2794 -0.1016) (xy 0.2794 0.9906) (xy -0.2794 0.9906)
			)
			(stroke
				(width 0)
				(type default)
			)
			(fill no)
			(layer "F.CrtYd")
		)
		(fp_line
			(start -0.2794 -0.1016)
			(end -0.2794 0.9906)
			(stroke
				(width 0.1)
				(type default)
			)
			(layer "F.Fab")
		)
		(fp_line
			(start -0.2794 0.9906)
			(end 0.2794 0.9906)
			(stroke
				(width 0.1)
				(type default)
			)
			(layer "F.Fab")
		)
		(fp_line
			(start 0.2794 -0.1016)
			(end -0.2794 -0.1016)
			(stroke
				(width 0.1)
				(type default)
			)
			(layer "F.Fab")
		)
		(fp_line
			(start 0.2794 0.9906)
			(end 0.2794 -0.1016)
			(stroke
				(width 0.1)
				(type default)
			)
			(layer "F.Fab")
		)
		(pad "1" smd rect
			(at 0 0)
			(size 0.508 0.508)
			(layers "F.Cu" "F.Mask" "F.Paste")
			(net "PVCCIO_CPU1")
		)
		(pad "2" smd rect
			(at 0 0.889)
			(size 0.508 0.508)
			(layers "F.Cu" "F.Mask" "F.Paste")
			(net "VSENSE_PMAX_CPU1")
		)
		(zone
			(layer "F.Cu")
			(hatch none 0.5)
			(connect_pads
				(clearance 0)
			)
			(min_thickness 0.25)
			(keepout
				(tracks allowed)
				(vias not_allowed)
				(pads allowed)
				(copperpour not_allowed)
				(footprints allowed)
			)
			(placement
				(enabled no)
				(sheetname "")
			)
			(fill
				(thermal_gap 0.5)
				(thermal_bridge_width 0.5)
				(island_removal_mode 0)
			)
			(polygon
				(pts
					(xy 108.458 -69.596) (xy 108.966 -69.596) (xy 108.966 -69.215) (xy 108.458 -69.215)
				)
			)
		)
		(zone
			(layer "F.Cu")
			(hatch none 0.5)
			(connect_pads
				(clearance 0)
			)
			(min_thickness 0.25)
			(keepout
				(tracks not_allowed)
				(vias allowed)
				(pads allowed)
				(copperpour not_allowed)
				(footprints allowed)
			)
			(placement
				(enabled no)
				(sheetname "")
			)
			(fill
				(thermal_gap 0.5)
				(thermal_bridge_width 0.5)
				(island_removal_mode 0)
			)
			(polygon
				(pts
					(xy 108.458 -69.215) (xy 108.966 -69.215) (xy 108.966 -69.596) (xy 108.458 -69.596)
				)
			)
		)
	)
)
